(kicad_pcb
	(version 20260206)
	(generator "pcbnew")
	(generator_version "10.0")
	(general
		(thickness 1.6)
		(legacy_teardrops no)
	)
	(paper "A4")
	(title_block
		(title "peb — Lightning_PEB_BRD.brd")
		(comment 1 "Lightning (Wiwynn / Facebook NVMe JBOF) / footprints 562-567 of 2563")
	)
	(layers
		(0 "F.Cu" signal "TOP")
		(4 "In1.Cu" signal "L2GND")
		(6 "In2.Cu" signal "L3")
		(8 "In3.Cu" signal "L4VCC")
		(10 "In4.Cu" signal "L5VCC")
		(12 "In5.Cu" signal "L6")
		(14 "In6.Cu" signal "L7GND")
		(2 "B.Cu" signal "BOTTOM")
		(9 "F.Adhes" user "F.Adhesive")
		(11 "B.Adhes" user "B.Adhesive")
		(13 "F.Paste" user "Package Geometry/Pastemask Top")
		(15 "B.Paste" user "Package Geometry/Pastemask Bottom")
		(5 "F.SilkS" user "Ref Des/Silkscreen Top")
		(7 "B.SilkS" user "Ref Des/Silkscreen Bottom")
		(1 "F.Mask" user "Board Geometry/Soldermask Top")
		(3 "B.Mask" user "Board Geometry/Soldermask Bottom")
		(17 "Dwgs.User" user "User.Drawings")
		(19 "Cmts.User" user "User.Comments")
		(21 "Eco1.User" user "User.Eco1")
		(23 "Eco2.User" user "User.Eco2")
		(25 "Edge.Cuts" user "Board Geometry/Outline")
		(27 "Margin" user)
		(31 "F.CrtYd" user "Package Geometry/Place Bound Top")
		(29 "B.CrtYd" user "Package Geometry/Place Bound Bottom")
		(35 "F.Fab" user "Ref Des/Assembly Top")
		(33 "B.Fab" user "Ref Des/Assembly Bottom")
	)
	(footprint ""
		(layer "F.Cu")
		(at 303.784 -33.528)
		(property "Reference" "C25"
			(at 0 0 0)
			(layer "F.SilkS")
			(hide yes)
			(effects
				(font
					(size 1.27 1.27)
				)
			)
		)
		(property "Value" "SCD22U10V2KX-1GP"
			(at 1.1811 -2.7051 0)
			(unlocked yes)
			(layer "F.Fab")
			(hide yes)
			(effects
				(font
					(size 1.016 1.016)
					(thickness 0.1524)
				)
			)
		)
		(property "Device Type" "C402H22"
			(at 1.1811 -4.2291 0)
			(unlocked yes)
			(layer "F.Fab")
			(hide yes)
			(effects
				(font
					(size 1.016 1.016)
					(thickness 0.1524)
				)
			)
		)
		(duplicate_pad_numbers_are_jumpers no)
		(fp_rect
			(start -0.4318 0.9525)
			(end 0.4318 -0.9525)
			(stroke
				(width 0)
				(type default)
			)
			(fill no)
			(layer "F.CrtYd")
		)
		(fp_rect
			(start -0.4318 0.9525)
			(end 0.4318 -0.9525)
			(stroke
				(width 0)
				(type default)
			)
			(fill no)
			(layer "F.Fab")
		)
		(pad "1" smd custom
			(at 0 -0.4445)
			(size 0.1524 0.1524)
			(layers "F.Cu" "F.Mask" "F.Paste")
			(net "PCIE_TX_CAP_P7")
			(options
				(clearance outline)
				(anchor circle)
			)
			(primitives
				(gr_poly
					(pts
						(arc
							(start 0.3048 -0.2032)
							(mid 0.275042 -0.275042)
							(end 0.2032 -0.3048)
						)
						(arc
							(start -0.2032 -0.3048)
							(mid -0.275042 -0.275042)
							(end -0.3048 -0.2032)
						)
						(arc
							(start -0.3048 0.2032)
							(mid -0.275042 0.275042)
							(end -0.2032 0.3048)
						)
						(arc
							(start 0.2032 0.3048)
							(mid 0.275042 0.275042)
							(end 0.3048 0.2032)
						)
					)
					(width 0)
					(fill yes)
				)
			)
		)
		(pad "2" smd custom
			(at 0 0.4445)
			(size 0.1524 0.1524)
			(layers "F.Cu" "F.Mask" "F.Paste")
			(net "PCIE_TX_P7")
			(options
				(clearance outline)
				(anchor circle)
			)
			(primitives
				(gr_poly
					(pts
						(arc
							(start 0.3048 -0.2032)
							(mid 0.275042 -0.275042)
							(end 0.2032 -0.3048)
						)
						(arc
							(start -0.2032 -0.3048)
							(mid -0.275042 -0.275042)
							(end -0.3048 -0.2032)
						)
						(arc
							(start -0.3048 0.2032)
							(mid -0.275042 0.275042)
							(end -0.2032 0.3048)
						)
						(arc
							(start 0.2032 0.3048)
							(mid 0.275042 0.275042)
							(end 0.3048 0.2032)
						)
					)
					(width 0)
					(fill yes)
				)
			)
		)
	)
	(footprint ""
		(layer "F.Cu")
		(at 20.9296 -139.8016 -90)
		(property "Reference" "R614"
			(at 0 0 270)
			(layer "F.SilkS")
			(hide yes)
			(effects
				(font
					(size 1.27 1.27)
				)
			)
		)
		(property "Value" "0R2J-2-GP"
			(at 0.064008 -3.993896 270)
			(unlocked yes)
			(layer "F.Fab")
			(hide yes)
			(effects
				(font
					(size 1.016 1.016)
					(thickness 0.1524)
				)
			)
		)
		(property "Device Type" "R402H16"
			(at 0.064008 -5.517896 270)
			(unlocked yes)
			(layer "F.Fab")
			(hide yes)
			(effects
				(font
					(size 1.016 1.016)
					(thickness 0.1524)
				)
			)
		)
		(duplicate_pad_numbers_are_jumpers no)
		(fp_line
			(start -0.508 -0.9398)
			(end -0.508 0.9398)
			(stroke
				(width 0.1524)
				(type default)
			)
			(layer "F.SilkS")
		)
		(fp_line
			(start 0.508 -0.9398)
			(end -0.508 -0.9398)
			(stroke
				(width 0.1524)
				(type default)
			)
			(layer "F.SilkS")
		)
		(fp_rect
			(start -0.508 0.9398)
			(end 0.508 -0.9398)
			(stroke
				(width 0)
				(type default)
			)
			(fill no)
			(layer "F.CrtYd")
		)
		(fp_rect
			(start -0.508 0.9398)
			(end 0.508 -0.9398)
			(stroke
				(width 0)
				(type default)
			)
			(fill no)
			(layer "F.Fab")
		)
		(pad "1" smd custom
			(at 0 -0.4445 270)
			(size 0.1397 0.1397)
			(layers "F.Cu" "F.Mask" "F.Paste")
			(net "BMC_SELF_HW_RST_R")
			(options
				(clearance outline)
				(anchor circle)
			)
			(primitives
				(gr_poly
					(pts
						(arc
							(start -0.1778 -0.2794)
							(mid -0.249642 -0.249642)
							(end -0.2794 -0.1778)
						)
						(arc
							(start -0.2794 0.1778)
							(mid -0.249642 0.249642)
							(end -0.1778 0.2794)
						)
						(arc
							(start 0.1778 0.2794)
							(mid 0.249642 0.249642)
							(end 0.2794 0.1778)
						)
						(arc
							(start 0.2794 -0.1778)
							(mid 0.249642 -0.249642)
							(end 0.1778 -0.2794)
						)
					)
					(width 0)
					(fill yes)
				)
			)
		)
		(pad "2" smd custom
			(at 0 0.4445 270)
			(size 0.1397 0.1397)
			(layers "F.Cu" "F.Mask" "F.Paste")
			(net "BMC_SELF_HW_RST")
			(options
				(clearance outline)
				(anchor circle)
			)
			(primitives
				(gr_poly
					(pts
						(arc
							(start -0.1778 -0.2794)
							(mid -0.249642 -0.249642)
							(end -0.2794 -0.1778)
						)
						(arc
							(start -0.2794 0.1778)
							(mid -0.249642 0.249642)
							(end -0.1778 0.2794)
						)
						(arc
							(start 0.1778 0.2794)
							(mid 0.249642 0.249642)
							(end 0.2794 0.1778)
						)
						(arc
							(start 0.2794 -0.1778)
							(mid 0.249642 -0.249642)
							(end 0.1778 -0.2794)
						)
					)
					(width 0)
					(fill yes)
				)
			)
		)
	)
	(footprint ""
		(layer "F.Cu")
		(at 51.37404 -73.483724 -90)
		(property "Reference" "R941"
			(at 0 0 270)
			(layer "F.SilkS")
			(hide yes)
			(effects
				(font
					(size 1.27 1.27)
				)
			)
		)
		(property "Value" "0R2J-2-GP"
			(at 0.064008 -3.99415 270)
			(unlocked yes)
			(layer "F.Fab")
			(hide yes)
			(effects
				(font
					(size 1.016 1.016)
					(thickness 0.1524)
				)
			)
		)
		(property "Device Type" "R402H16"
			(at 0.064008 -5.51815 270)
			(unlocked yes)
			(layer "F.Fab")
			(hide yes)
			(effects
				(font
					(size 1.016 1.016)
					(thickness 0.1524)
				)
			)
		)
		(duplicate_pad_numbers_are_jumpers no)
		(fp_line
			(start -0.508254 -0.940054)
			(end -0.508 0.939546)
			(stroke
				(width 0.1524)
				(type default)
			)
			(layer "F.SilkS")
		)
		(fp_line
			(start 0.508 -0.940054)
			(end -0.508254 -0.940054)
			(stroke
				(width 0.1524)
				(type default)
			)
			(layer "F.SilkS")
		)
		(fp_rect
			(start -0.508 0.939546)
			(end 0.508 -0.940054)
			(stroke
				(width 0)
				(type default)
			)
			(fill no)
			(layer "F.CrtYd")
		)
		(fp_rect
			(start -0.508 0.939546)
			(end 0.508 -0.940054)
			(stroke
				(width 0)
				(type default)
			)
			(fill no)
			(layer "F.Fab")
		)
		(pad "1" smd custom
			(at 0 -0.4445 270)
			(size 0.1397 0.1397)
			(layers "F.Cu" "F.Mask" "F.Paste")
			(net "BMC_R_RXD5")
			(options
				(clearance outline)
				(anchor circle)
			)
			(primitives
				(gr_poly
					(pts
						(arc
							(start -0.1778 -0.2794)
							(mid -0.249642 -0.249642)
							(end -0.2794 -0.1778)
						)
						(arc
							(start -0.2794 0.1778)
							(mid -0.249642 0.249642)
							(end -0.1778 0.2794)
						)
						(arc
							(start 0.1778 0.2794)
							(mid 0.249642 0.249642)
							(end 0.2794 0.1778)
						)
						(arc
							(start 0.2794 -0.1778)
							(mid 0.249642 -0.249642)
							(end 0.1778 -0.2794)
						)
					)
					(width 0)
					(fill yes)
				)
			)
		)
		(pad "2" smd custom
			(at 0 0.4445 270)
			(size 0.1397 0.1397)
			(layers "F.Cu" "F.Mask" "F.Paste")
			(net "BMC_RXD5")
			(options
				(clearance outline)
				(anchor circle)
			)
			(primitives
				(gr_poly
					(pts
						(arc
							(start -0.1778 -0.2794)
							(mid -0.249642 -0.249642)
							(end -0.2794 -0.1778)
						)
						(arc
							(start -0.2794 0.1778)
							(mid -0.249642 0.249642)
							(end -0.1778 0.2794)
						)
						(arc
							(start 0.1778 0.2794)
							(mid 0.249642 0.249642)
							(end 0.2794 0.1778)
						)
						(arc
							(start 0.2794 -0.1778)
							(mid 0.249642 -0.249642)
							(end 0.1778 -0.2794)
						)
					)
					(width 0)
					(fill yes)
				)
			)
		)
	)
	(footprint ""
		(layer "F.Cu")
		(at 171.408598 -70.787768 180)
		(property "Reference" "PTC10"
			(at 0 0 180)
			(layer "F.SilkS")
			(hide yes)
			(effects
				(font
					(size 1.27 1.27)
				)
			)
		)
		(property "Value" "SE470UF2VDM-GP"
			(at 0 -9.6012 180)
			(unlocked yes)
			(layer "F.Fab")
			(hide yes)
			(effects
				(font
					(size 1.016 1.016)
					(thickness 0.1524)
				)
			)
		)
		(property "Device Type" "CT7343H83"
			(at 0 -11.1252 180)
			(unlocked yes)
			(layer "F.Fab")
			(hide yes)
			(effects
				(font
					(size 1.016 1.016)
					(thickness 0.1524)
				)
			)
		)
		(duplicate_pad_numbers_are_jumpers no)
		(fp_line
			(start 2.286 4.8768)
			(end -2.286 4.8768)
			(stroke
				(width 0.1524)
				(type default)
			)
			(layer "F.SilkS")
		)
		(fp_line
			(start 2.286 2.032)
			(end 2.286 4.8768)
			(stroke
				(width 0.1524)
				(type default)
			)
			(layer "F.SilkS")
		)
		(fp_line
			(start 2.286 -2.032)
			(end 2.286 -4.8768)
			(stroke
				(width 0.1524)
				(type default)
			)
			(layer "F.SilkS")
		)
		(fp_line
			(start 2.286 -4.8768)
			(end -2.286 -4.8768)
			(stroke
				(width 0.1524)
				(type default)
			)
			(layer "F.SilkS")
		)
		(fp_line
			(start 2.1082 -4.699)
			(end -2.1082 -4.699)
			(stroke
				(width 0.508)
				(type default)
			)
			(layer "F.SilkS")
		)
		(fp_line
			(start -2.286 4.8768)
			(end -2.286 2.032)
			(stroke
				(width 0.1524)
				(type default)
			)
			(layer "F.SilkS")
		)
		(fp_line
			(start -2.286 -4.8768)
			(end -2.286 -2.032)
			(stroke
				(width 0.1524)
				(type default)
			)
			(layer "F.SilkS")
		)
		(fp_rect
			(start -2.1463 3.6449)
			(end 2.1463 -3.6449)
			(stroke
				(width 0)
				(type default)
			)
			(fill no)
			(layer "F.CrtYd")
		)
		(fp_poly
			(pts
				(xy -2.54 4.953) (xy -2.54 4.2926) (xy -3.81 4.2926) (xy -3.81 -4.2926) (xy -2.54 -4.2926) (xy -2.54 -4.953)
				(xy 2.54 -4.953) (xy 2.54 -4.2926) (xy 3.81 -4.2926) (xy 3.81 -1.6256) (xy 2.1463 -1.6256) (xy 2.1463 -3.6449)
				(xy -2.1463 -3.6449) (xy -2.1463 3.6449) (xy 2.1463 3.6449) (xy 2.1463 -1.6129) (xy 3.81 -1.6129)
				(xy 3.81 4.2926) (xy 2.54 4.2926) (xy 2.54 4.953)
			)
			(stroke
				(width 0)
				(type default)
			)
			(fill no)
			(layer "F.CrtYd")
		)
		(fp_rect
			(start 2.54 4.2926)
			(end 3.81 -4.2926)
			(stroke
				(width 0)
				(type default)
			)
			(fill no)
			(layer "F.Fab")
		)
		(fp_rect
			(start -2.54 4.953)
			(end 2.54 -4.953)
			(stroke
				(width 0)
				(type default)
			)
			(fill no)
			(layer "F.Fab")
		)
		(fp_rect
			(start -3.81 4.2926)
			(end -2.54 -4.2926)
			(stroke
				(width 0)
				(type default)
			)
			(fill no)
			(layer "F.Fab")
		)
		(pad "1" smd rect
			(at 0 -3.1496 180)
			(size 2.413 2.286)
			(layers "F.Cu" "F.Mask" "F.Paste")
			(net "P0V9")
		)
		(pad "2" smd rect
			(at 0 3.1496 180)
			(size 2.413 2.286)
			(layers "F.Cu" "F.Mask" "F.Paste")
			(net "GND")
		)
		(zone
			(layer "F.Cu")
			(hatch none 0.5)
			(connect_pads
				(clearance 0)
			)
			(min_thickness 0.25)
			(keepout
				(tracks allowed)
				(vias not_allowed)
				(pads allowed)
				(copperpour not_allowed)
				(footprints allowed)
			)
			(placement
				(enabled no)
				(sheetname "")
			)
			(fill
				(thermal_gap 0.5)
				(thermal_bridge_width 0.5)
				(island_removal_mode 0)
			)
			(polygon
				(pts
					(xy 169.897298 -69.098668) (xy 169.897298 -66.190368) (xy 172.919898 -66.190368) (xy 172.919898 -69.085968)
					(xy 172.919898 -69.416168) (xy 169.897298 -69.416168)
				)
			)
		)
		(zone
			(layer "F.Cu")
			(hatch none 0.5)
			(connect_pads
				(clearance 0)
			)
			(min_thickness 0.25)
			(keepout
				(tracks allowed)
				(vias not_allowed)
				(pads allowed)
				(copperpour not_allowed)
				(footprints allowed)
			)
			(placement
				(enabled no)
				(sheetname "")
			)
			(fill
				(thermal_gap 0.5)
				(thermal_bridge_width 0.5)
				(island_removal_mode 0)
			)
			(polygon
				(pts
					(xy 172.919898 -75.385168) (xy 169.897298 -75.385168) (xy 169.897298 -72.489568) (xy 169.897298 -72.159368)
					(xy 172.919898 -72.159368) (xy 172.919898 -72.489568)
				)
			)
		)
	)
	(footprint ""
		(layer "F.Cu")
		(at 70.1802 -162.2806 -90)
		(property "Reference" "PR43"
			(at 0 0 270)
			(layer "F.SilkS")
			(hide yes)
			(effects
				(font
					(size 1.27 1.27)
				)
			)
		)
		(property "Value" "10KR2F-2-GP"
			(at 0.064008 -3.993896 270)
			(unlocked yes)
			(layer "F.Fab")
			(hide yes)
			(effects
				(font
					(size 1.016 1.016)
					(thickness 0.1524)
				)
			)
		)
		(property "Device Type" "R402H16"
			(at 0.064008 -5.517896 270)
			(unlocked yes)
			(layer "F.Fab")
			(hide yes)
			(effects
				(font
					(size 1.016 1.016)
					(thickness 0.1524)
				)
			)
		)
		(duplicate_pad_numbers_are_jumpers no)
		(fp_line
			(start -0.508 -0.9398)
			(end -0.508 0.9398)
			(stroke
				(width 0.1524)
				(type default)
			)
			(layer "F.SilkS")
		)
		(fp_line
			(start 0.508 -0.9398)
			(end -0.508 -0.9398)
			(stroke
				(width 0.1524)
				(type default)
			)
			(layer "F.SilkS")
		)
		(fp_rect
			(start -0.508 0.9398)
			(end 0.508 -0.9398)
			(stroke
				(width 0)
				(type default)
			)
			(fill no)
			(layer "F.CrtYd")
		)
		(fp_rect
			(start -0.508 0.9398)
			(end 0.508 -0.9398)
			(stroke
				(width 0)
				(type default)
			)
			(fill no)
			(layer "F.Fab")
		)
		(pad "1" smd custom
			(at 0 -0.4445 270)
			(size 0.1397 0.1397)
			(layers "F.Cu" "F.Mask" "F.Paste")
			(net "P3V3_STBY")
			(options
				(clearance outline)
				(anchor circle)
			)
			(primitives
				(gr_poly
					(pts
						(arc
							(start -0.1778 -0.2794)
							(mid -0.249642 -0.249642)
							(end -0.2794 -0.1778)
						)
						(arc
							(start -0.2794 0.1778)
							(mid -0.249642 0.249642)
							(end -0.1778 0.2794)
						)
						(arc
							(start 0.1778 0.2794)
							(mid 0.249642 0.249642)
							(end 0.2794 0.1778)
						)
						(arc
							(start 0.2794 -0.1778)
							(mid 0.249642 -0.249642)
							(end 0.1778 -0.2794)
						)
					)
					(width 0)
					(fill yes)
				)
			)
		)
		(pad "2" smd custom
			(at 0 0.4445 270)
			(size 0.1397 0.1397)
			(layers "F.Cu" "F.Mask" "F.Paste")
			(net "PWRGD_P1V538_STBY")
			(options
				(clearance outline)
				(anchor circle)
			)
			(primitives
				(gr_poly
					(pts
						(arc
							(start -0.1778 -0.2794)
							(mid -0.249642 -0.249642)
							(end -0.2794 -0.1778)
						)
						(arc
							(start -0.2794 0.1778)
							(mid -0.249642 0.249642)
							(end -0.1778 0.2794)
						)
						(arc
							(start 0.1778 0.2794)
							(mid 0.249642 0.249642)
							(end 0.2794 0.1778)
						)
						(arc
							(start 0.2794 -0.1778)
							(mid 0.249642 -0.249642)
							(end 0.1778 -0.2794)
						)
					)
					(width 0)
					(fill yes)
				)
			)
		)
	)
	(footprint ""
		(layer "F.Cu")
		(at 20.267168 -95.233998 180)
		(property "Reference" "Q20"
			(at 0 0 180)
			(layer "F.SilkS")
			(hide yes)
			(effects
				(font
					(size 1.27 1.27)
				)
			)
		)
		(property "Value" "2N7002-7F-GP"
			(at 0.127 -8.9662 180)
			(unlocked yes)
			(layer "F.Fab")
			(hide yes)
			(effects
				(font
					(size 1.016 1.016)
					(thickness 0.1524)
				)
			)
		)
		(property "Device Type" "SOT23DGS2D4H44"
			(at 0.127 -10.4902 180)
			(unlocked yes)
			(layer "F.Fab")
			(hide yes)
			(effects
				(font
					(size 1.016 1.016)
					(thickness 0.1524)
				)
			)
		)
		(duplicate_pad_numbers_are_jumpers no)
		(fp_line
			(start 1.651 1.778)
			(end 1.651 -1.778)
			(stroke
				(width 0.1524)
				(type default)
			)
			(layer "F.SilkS")
		)
		(fp_line
			(start 1.651 -1.778)
			(end -1.651 -1.778)
			(stroke
				(width 0.1524)
				(type default)
			)
			(layer "F.SilkS")
		)
		(fp_line
			(start -1.651 1.778)
			(end 1.651 1.778)
			(stroke
				(width 0.1524)
				(type default)
			)
			(layer "F.SilkS")
		)
		(fp_line
			(start -1.651 -1.778)
			(end -1.651 1.778)
			(stroke
				(width 0.1524)
				(type default)
			)
			(layer "F.SilkS")
		)
		(fp_poly
			(pts
				(xy -1.778 1.8796) (xy -1.778 -1.8796) (xy 1.778 -1.8796) (xy 1.778 1.8796)
			)
			(stroke
				(width 0)
				(type default)
			)
			(fill no)
			(layer "F.CrtYd")
		)
		(fp_poly
			(pts
				(xy -1.778 1.8796) (xy -1.778 -1.8796) (xy 1.778 -1.8796) (xy 1.778 1.8796)
			)
			(stroke
				(width 0)
				(type default)
			)
			(fill no)
			(layer "F.Fab")
		)
		(pad "D" smd custom
			(at 0 -0.9525 180)
			(size 0.1905 0.1905)
			(layers "F.Cu" "F.Mask" "F.Paste")
			(net "FM_TPM_PRES_RST_N")
			(options
				(clearance outline)
				(anchor circle)
			)
			(primitives
				(gr_poly
					(pts
						(arc
							(start -0.1778 0.5715)
							(mid -0.321484 0.511984)
							(end -0.381 0.3683)
						)
						(arc
							(start -0.381 -0.3683)
							(mid -0.321484 -0.511984)
							(end -0.1778 -0.5715)
						)
						(arc
							(start 0.1778 -0.5715)
							(mid 0.321484 -0.511984)
							(end 0.381 -0.3683)
						)
						(arc
							(start 0.381 0.3683)
							(mid 0.321484 0.511984)
							(end 0.1778 0.5715)
						)
					)
					(width 0)
					(fill yes)
				)
			)
		)
		(pad "G" smd custom
			(at -0.98425 0.9525 180)
			(size 0.1905 0.1905)
			(layers "F.Cu" "F.Mask" "F.Paste")
			(net "Q20_G")
			(options
				(clearance outline)
				(anchor circle)
			)
			(primitives
				(gr_poly
					(pts
						(arc
							(start -0.1778 0.5715)
							(mid -0.321484 0.511984)
							(end -0.381 0.3683)
						)
						(arc
							(start -0.381 -0.3683)
							(mid -0.321484 -0.511984)
							(end -0.1778 -0.5715)
						)
						(arc
							(start 0.1778 -0.5715)
							(mid 0.321484 -0.511984)
							(end 0.381 -0.3683)
						)
						(arc
							(start 0.381 0.3683)
							(mid 0.321484 0.511984)
							(end 0.1778 0.5715)
						)
					)
					(width 0)
					(fill yes)
				)
			)
		)
		(pad "S" smd custom
			(at 0.98425 0.9525 180)
			(size 0.1905 0.1905)
			(layers "F.Cu" "F.Mask" "F.Paste")
			(net "GND")
			(options
				(clearance outline)
				(anchor circle)
			)
			(primitives
				(gr_poly
					(pts
						(arc
							(start -0.1778 0.5715)
							(mid -0.321484 0.511984)
							(end -0.381 0.3683)
						)
						(arc
							(start -0.381 -0.3683)
							(mid -0.321484 -0.511984)
							(end -0.1778 -0.5715)
						)
						(arc
							(start 0.1778 -0.5715)
							(mid 0.321484 -0.511984)
							(end 0.381 -0.3683)
						)
						(arc
							(start 0.381 0.3683)
							(mid 0.321484 0.511984)
							(end 0.1778 0.5715)
						)
					)
					(width 0)
					(fill yes)
				)
			)
		)
	)
)
